(kicad_pcb
	(version 20260206)
	(generator "pcbnew")
	(generator_version "10.0")
	(general
		(thickness 1.6)
		(legacy_teardrops no)
	)
	(paper "A4")
	(title_block
		(title "Bryce Canyon_R.DPB_16317-1_OCP.brd")
		(comment 1 "Bryce Canyon / footprints 684-686 of 2099")
	)
	(layers
		(0 "F.Cu" signal "TOP")
		(4 "In1.Cu" signal "L2GND")
		(6 "In2.Cu" signal "L3")
		(8 "In3.Cu" signal "L4VCC")
		(10 "In4.Cu" signal "L5VCC")
		(12 "In5.Cu" signal "L6")
		(14 "In6.Cu" signal "L7GND")
		(2 "B.Cu" signal "BOTTOM")
		(9 "F.Adhes" user "F.Adhesive")
		(11 "B.Adhes" user "B.Adhesive")
		(13 "F.Paste" user "Package Geometry/Pastemask Top")
		(15 "B.Paste" user "Package Geometry/Pastemask Bottom")
		(5 "F.SilkS" user "Ref Des/Silkscreen Top")
		(7 "B.SilkS" user "Ref Des/Silkscreen Bottom")
		(1 "F.Mask" user "Board Geometry/Soldermask Top")
		(3 "B.Mask" user "Board Geometry/Soldermask Bottom")
		(17 "Dwgs.User" user "User.Drawings")
		(19 "Cmts.User" user "User.Comments")
		(21 "Eco1.User" user "User.Eco1")
		(23 "Eco2.User" user "User.Eco2")
		(25 "Edge.Cuts" user "Board Geometry/Outline")
		(27 "Margin" user)
		(31 "F.CrtYd" user "Package Geometry/Place Bound Top")
		(29 "B.CrtYd" user "Package Geometry/Place Bound Bottom")
		(35 "F.Fab" user "Ref Des/Assembly Top")
		(33 "B.Fab" user "Ref Des/Assembly Bottom")
	)
	(footprint ""
		(layer "F.Cu")
		(at 91.300046 -258.910074 -90)
		(property "Reference" "HDDSAS2"
			(at 0 0 270)
			(layer "F.SilkS")
			(hide yes)
			(effects
				(font
					(size 1.27 1.27)
				)
			)
		)
		(property "Value" "SKT-SAS15P-14P-45-GP"
			(at -20.7645 -8.9789 270)
			(unlocked yes)
			(layer "F.Fab")
			(hide yes)
			(effects
				(font
					(size 1.016 1.016)
					(thickness 0.1524)
				)
			)
		)
		(property "Device Type" "10120818-001C-TRLF"
			(at -20.7645 -10.5029 270)
			(unlocked yes)
			(layer "F.Fab")
			(hide yes)
			(effects
				(font
					(size 1.016 1.016)
					(thickness 0.1524)
				)
			)
		)
		(duplicate_pad_numbers_are_jumpers no)
		(fp_line
			(start 1.651 4.2926)
			(end 1.651 3.0099)
			(stroke
				(width 0.1524)
				(type default)
			)
			(layer "F.SilkS")
		)
		(fp_line
			(start 8.509 4.2926)
			(end 1.651 4.2926)
			(stroke
				(width 0.1524)
				(type default)
			)
			(layer "F.SilkS")
		)
		(fp_line
			(start -23.4188 3.0099)
			(end -23.4188 -3.2512)
			(stroke
				(width 0.1524)
				(type default)
			)
			(layer "F.SilkS")
		)
		(fp_line
			(start 1.651 3.0099)
			(end -23.4188 3.0099)
			(stroke
				(width 0.1524)
				(type default)
			)
			(layer "F.SilkS")
		)
		(fp_line
			(start 8.509 3.0099)
			(end 8.509 4.2926)
			(stroke
				(width 0.1524)
				(type default)
			)
			(layer "F.SilkS")
		)
		(fp_line
			(start 23.4188 3.0099)
			(end 8.509 3.0099)
			(stroke
				(width 0.1524)
				(type default)
			)
			(layer "F.SilkS")
		)
		(fp_line
			(start -23.4188 -3.2512)
			(end 23.4188 -3.2512)
			(stroke
				(width 0.1524)
				(type default)
			)
			(layer "F.SilkS")
		)
		(fp_line
			(start 23.4188 -3.2512)
			(end 23.4188 3.0099)
			(stroke
				(width 0.1524)
				(type default)
			)
			(layer "F.SilkS")
		)
		(fp_line
			(start 15.5067 -3.3401)
			(end 16.2687 -3.3401)
			(stroke
				(width 0.3302)
				(type default)
			)
			(layer "F.SilkS")
		)
		(fp_poly
			(pts
				(xy 15.868904 -3.230372) (xy 16.503904 -3.865372) (xy 15.233904 -3.865372)
			)
			(stroke
				(width 0)
				(type default)
			)
			(fill yes)
			(layer "F.SilkS")
		)
		(fp_poly
			(pts
				(xy -22.8727 -2.7559) (xy 22.8727 -2.7559) (xy 22.8727 2.7559) (xy 8.255 2.7559) (xy 8.255 3.5179)
				(xy 1.905 3.5179) (xy 1.905 2.7559) (xy -22.8727 2.7559)
			)
			(stroke
				(width 0)
				(type default)
			)
			(fill no)
			(layer "F.CrtYd")
		)
		(fp_poly
			(pts
				(xy 1.397 4.5466) (xy 1.397 3.2639) (xy -23.6728 3.2639) (xy -23.6728 -3.5052) (xy 23.6728 -3.5052)
				(xy 23.6728 -0.00635) (xy 22.8727 -0.00635) (xy 22.8727 -2.7559) (xy -22.8727 -2.7559) (xy -22.8727 2.7559)
				(xy 1.905 2.7559) (xy 1.905 3.5179) (xy 8.255 3.5179) (xy 8.255 2.7559) (xy 22.8727 2.7559) (xy 22.8727 0.00635)
				(xy 23.6728 0.00635) (xy 23.6728 3.2639) (xy 8.763 3.2639) (xy 8.763 4.5466)
			)
			(stroke
				(width 0)
				(type default)
			)
			(fill no)
			(layer "F.CrtYd")
		)
		(fp_poly
			(pts
				(xy 1.397 4.5466) (xy 1.397 3.2639) (xy -23.6728 3.2639) (xy -23.6728 -3.5052) (xy 23.6728 -3.5052)
				(xy 23.6728 3.2639) (xy 8.763 3.2639) (xy 8.763 4.5466)
			)
			(stroke
				(width 0)
				(type default)
			)
			(fill no)
			(layer "F.Fab")
		)
		(pad "" np_thru_hole circle
			(at -18.874994 0 270)
			(size 0.254 0.254)
			(drill 1.3462)
			(layers "*.Cu" "*.Mask")
			(clearance 0.9017)
			(thermal_gap 0.9017)
		)
		(pad "" np_thru_hole circle
			(at 18.874994 0 270)
			(size 0.254 0.254)
			(drill 0.9398)
			(layers "*.Cu" "*.Mask")
			(clearance 0.6985)
			(thermal_gap 0.6985)
		)
		(pad "G1" smd rect
			(at 21.874988 0 270)
			(size 2.5908 2.5908)
			(layers "F.Cu" "F.Mask" "F.Paste")
			(net "GND")
		)
		(pad "G2" smd rect
			(at -21.874988 0 270)
			(size 2.5908 2.5908)
			(layers "F.Cu" "F.Mask" "F.Paste")
			(net "GND")
		)
		(pad "P1" smd rect
			(at 1.905 -1.82499 270)
			(size 0.6096 2.3622)
			(layers "F.Cu" "F.Mask" "F.Paste")
			(net "Net_1654")
		)
		(pad "P2" smd rect
			(at 0.635 -1.82499 270)
			(size 0.6096 2.3622)
			(layers "F.Cu" "F.Mask" "F.Paste")
			(net "Net_1655")
		)
		(pad "P3" smd rect
			(at -0.635 -1.82499 270)
			(size 0.6096 2.3622)
			(layers "F.Cu" "F.Mask" "F.Paste")
			(net "Net_1656")
		)
		(pad "P4" smd rect
			(at -1.905 -1.82499 270)
			(size 0.6096 2.3622)
			(layers "F.Cu" "F.Mask" "F.Paste")
			(net "GND")
		)
		(pad "P5" smd rect
			(at -3.175 -1.82499 270)
			(size 0.6096 2.3622)
			(layers "F.Cu" "F.Mask" "F.Paste")
			(net "HDD_PRSNT_2")
		)
		(pad "P6" smd rect
			(at -4.445 -1.82499 270)
			(size 0.6096 2.3622)
			(layers "F.Cu" "F.Mask" "F.Paste")
			(net "GND")
		)
		(pad "P7" smd rect
			(at -5.715 -1.82499 270)
			(size 0.6096 2.3622)
			(layers "F.Cu" "F.Mask" "F.Paste")
			(net "5V_PRE_2")
		)
		(pad "P8" smd rect
			(at -6.985 -1.82499 270)
			(size 0.6096 2.3622)
			(layers "F.Cu" "F.Mask" "F.Paste")
			(net "P5V_HDD2")
		)
		(pad "P9" smd rect
			(at -8.255 -1.82499 270)
			(size 0.6096 2.3622)
			(layers "F.Cu" "F.Mask" "F.Paste")
			(net "P5V_HDD2")
		)
		(pad "P10" smd rect
			(at -9.525 -1.82499 270)
			(size 0.6096 2.3622)
			(layers "F.Cu" "F.Mask" "F.Paste")
			(net "GND")
		)
		(pad "P11" smd rect
			(at -10.795 -1.82499 270)
			(size 0.6096 2.3622)
			(layers "F.Cu" "F.Mask" "F.Paste")
			(net "ACT_HDD_2")
		)
		(pad "P12" smd rect
			(at -12.065 -1.82499 270)
			(size 0.6096 2.3622)
			(layers "F.Cu" "F.Mask" "F.Paste")
			(net "GND")
		)
		(pad "P13" smd rect
			(at -13.335 -1.82499 270)
			(size 0.6096 2.3622)
			(layers "F.Cu" "F.Mask" "F.Paste")
			(net "12V_PRE_2")
		)
		(pad "P14" smd rect
			(at -14.605 -1.82499 270)
			(size 0.6096 2.3622)
			(layers "F.Cu" "F.Mask" "F.Paste")
			(net "P12V_HDD2")
		)
		(pad "P15" smd rect
			(at -15.875 -1.82499 270)
			(size 0.6096 2.3622)
			(layers "F.Cu" "F.Mask" "F.Paste")
			(net "P12V_HDD2")
		)
		(pad "S1" smd rect
			(at 15.875 -1.82499 270)
			(size 0.6096 2.3622)
			(layers "F.Cu" "F.Mask" "F.Paste")
			(net "GND")
		)
		(pad "S2" smd rect
			(at 14.605 -1.82499 270)
			(size 0.6096 2.3622)
			(layers "F.Cu" "F.Mask" "F.Paste")
			(net "SAS_HDD_RX_P2")
		)
		(pad "S3" smd rect
			(at 13.335 -1.82499 270)
			(size 0.6096 2.3622)
			(layers "F.Cu" "F.Mask" "F.Paste")
			(net "SAS_HDD_RX_N2")
		)
		(pad "S4" smd rect
			(at 12.065 -1.82499 270)
			(size 0.6096 2.3622)
			(layers "F.Cu" "F.Mask" "F.Paste")
			(net "GND")
		)
		(pad "S5" smd rect
			(at 10.795 -1.82499 270)
			(size 0.6096 2.3622)
			(layers "F.Cu" "F.Mask" "F.Paste")
			(net "PHY_DRV_B_TO_SCC_B_2_DN")
		)
		(pad "S6" smd rect
			(at 9.525 -1.82499 270)
			(size 0.6096 2.3622)
			(layers "F.Cu" "F.Mask" "F.Paste")
			(net "PHY_DRV_B_TO_SCC_B_2_DP")
		)
		(pad "S7" smd rect
			(at 8.255 -1.82499 270)
			(size 0.6096 2.3622)
			(layers "F.Cu" "F.Mask" "F.Paste")
			(net "GND")
		)
		(pad "S8" smd rect
			(at 7.480046 2.845054 270)
			(size 0.508 2.3622)
			(layers "F.Cu" "F.Mask" "F.Paste")
			(net "GND")
		)
		(pad "S9" smd rect
			(at 6.679946 2.845054 270)
			(size 0.508 2.3622)
			(layers "F.Cu" "F.Mask" "F.Paste")
			(net "Net_453")
		)
		(pad "S10" smd rect
			(at 5.8801 2.845054 270)
			(size 0.508 2.3622)
			(layers "F.Cu" "F.Mask" "F.Paste")
			(net "Net_345")
		)
		(pad "S11" smd rect
			(at 5.08 2.845054 270)
			(size 0.508 2.3622)
			(layers "F.Cu" "F.Mask" "F.Paste")
			(net "GND")
		)
		(pad "S12" smd rect
			(at 4.2799 2.845054 270)
			(size 0.508 2.3622)
			(layers "F.Cu" "F.Mask" "F.Paste")
			(net "Net_381")
		)
		(pad "S13" smd rect
			(at 3.480054 2.845054 270)
			(size 0.508 2.3622)
			(layers "F.Cu" "F.Mask" "F.Paste")
			(net "Net_417")
		)
		(pad "S14" smd rect
			(at 2.679954 2.845054 270)
			(size 0.508 2.3622)
			(layers "F.Cu" "F.Mask" "F.Paste")
			(net "GND")
		)
		(zone
			(layer "F.Cu")
			(hatch none 0.5)
			(connect_pads
				(clearance 0)
			)
			(min_thickness 0.25)
			(keepout
				(tracks not_allowed)
				(vias allowed)
				(pads allowed)
				(copperpour not_allowed)
				(footprints allowed)
			)
			(placement
				(enabled no)
				(sheetname "")
			)
			(fill
				(thermal_gap 0.5)
				(thermal_bridge_width 0.5)
				(island_removal_mode 0)
			)
			(polygon
				(pts
					(xy 94.957646 -275.648674) (xy 87.883746 -275.648674) (xy 87.883746 -282.582874) (xy 88.988646 -282.582874)
					(xy 88.988646 -278.468074) (xy 93.611446 -278.468074) (xy 93.611446 -282.582874) (xy 94.957646 -282.582874)
				)
			)
		)
		(zone
			(layer "F.Cu")
			(hatch none 0.5)
			(connect_pads
				(clearance 0)
			)
			(min_thickness 0.25)
			(keepout
				(tracks allowed)
				(vias not_allowed)
				(pads allowed)
				(copperpour not_allowed)
				(footprints allowed)
			)
			(placement
				(enabled no)
				(sheetname "")
			)
			(fill
				(thermal_gap 0.5)
				(thermal_bridge_width 0.5)
				(island_removal_mode 0)
			)
			(polygon
				(pts
					(xy 94.957646 -275.648674) (xy 87.883746 -275.648674) (xy 87.883746 -282.582874) (xy 88.988646 -282.582874)
					(xy 88.988646 -278.468074) (xy 93.611446 -278.468074) (xy 93.611446 -282.582874) (xy 94.957646 -282.582874)
				)
			)
		)
		(zone
			(layer "F.Cu")
			(hatch none 0.5)
			(connect_pads
				(clearance 0)
			)
			(min_thickness 0.25)
			(keepout
				(tracks not_allowed)
				(vias allowed)
				(pads allowed)
				(copperpour not_allowed)
				(footprints allowed)
			)
			(placement
				(enabled no)
				(sheetname "")
			)
			(fill
				(thermal_gap 0.5)
				(thermal_bridge_width 0.5)
				(island_removal_mode 0)
			)
			(polygon
				(pts
					(xy 94.957646 -242.171474) (xy 87.883746 -242.171474) (xy 87.883746 -235.237274) (xy 88.988646 -235.237274)
					(xy 88.988646 -239.352074) (xy 93.611446 -239.352074) (xy 93.611446 -235.237274) (xy 94.957646 -235.237274)
				)
			)
		)
		(zone
			(layer "F.Cu")
			(hatch none 0.5)
			(connect_pads
				(clearance 0)
			)
			(min_thickness 0.25)
			(keepout
				(tracks allowed)
				(vias not_allowed)
				(pads allowed)
				(copperpour not_allowed)
				(footprints allowed)
			)
			(placement
				(enabled no)
				(sheetname "")
			)
			(fill
				(thermal_gap 0.5)
				(thermal_bridge_width 0.5)
				(island_removal_mode 0)
			)
			(polygon
				(pts
					(xy 94.957646 -242.171474) (xy 87.883746 -242.171474) (xy 87.883746 -235.237274) (xy 88.988646 -235.237274)
					(xy 88.988646 -239.352074) (xy 93.611446 -239.352074) (xy 93.611446 -235.237274) (xy 94.957646 -235.237274)
				)
			)
		)
		(zone
			(layers "F.Cu" "B.Cu" "In1.Cu" "In2.Cu" "In3.Cu" "In4.Cu" "In5.Cu" "In6.Cu")
			(hatch none 0.5)
			(connect_pads
				(clearance 0)
			)
			(min_thickness 0.25)
			(keepout
				(tracks not_allowed)
				(vias allowed)
				(pads allowed)
				(copperpour not_allowed)
				(footprints allowed)
			)
			(placement
				(enabled no)
				(sheetname "")
			)
			(fill
				(thermal_gap 0.5)
				(thermal_bridge_width 0.5)
				(island_removal_mode 0)
			)
			(polygon
				(pts
					(arc
						(start 92.074746 -240.03508)
						(mid 90.525346 -240.03508)
						(end 92.074746 -240.03508)
					)
				)
			)
		)
		(zone
			(layers "F.Cu" "B.Cu" "In1.Cu" "In2.Cu" "In3.Cu" "In4.Cu" "In5.Cu" "In6.Cu")
			(hatch none 0.5)
			(connect_pads
				(clearance 0)
			)
			(min_thickness 0.25)
			(keepout
				(tracks not_allowed)
				(vias allowed)
				(pads allowed)
				(copperpour not_allowed)
				(footprints allowed)
			)
			(placement
				(enabled no)
				(sheetname "")
			)
			(fill
				(thermal_gap 0.5)
				(thermal_bridge_width 0.5)
				(island_removal_mode 0)
			)
			(polygon
				(pts
					(arc
						(start 92.277946 -277.785068)
						(mid 90.322146 -277.785068)
						(end 92.277946 -277.785068)
					)
				)
			)
		)
	)
	(footprint ""
		(layer "F.Cu")
		(at 335.153 -358.3559)
		(property "Reference" "R145"
			(at 0 0 0)
			(layer "F.SilkS")
			(hide yes)
			(effects
				(font
					(size 1.27 1.27)
				)
			)
		)
		(property "Value" "200KR2F-L-GP"
			(at 0.064008 -3.993896 0)
			(unlocked yes)
			(layer "F.Fab")
			(hide yes)
			(effects
				(font
					(size 1.016 1.016)
					(thickness 0.1524)
				)
			)
		)
		(property "Device Type" "R402H16"
			(at 0.064008 -5.517896 0)
			(unlocked yes)
			(layer "F.Fab")
			(hide yes)
			(effects
				(font
					(size 1.016 1.016)
					(thickness 0.1524)
				)
			)
		)
		(duplicate_pad_numbers_are_jumpers no)
		(fp_line
			(start -0.508 -0.9398)
			(end -0.508 0.9398)
			(stroke
				(width 0.1524)
				(type default)
			)
			(layer "F.SilkS")
		)
		(fp_line
			(start 0.508 -0.9398)
			(end -0.508 -0.9398)
			(stroke
				(width 0.1524)
				(type default)
			)
			(layer "F.SilkS")
		)
		(fp_rect
			(start -0.508 0.9398)
			(end 0.508 -0.9398)
			(stroke
				(width 0)
				(type default)
			)
			(fill no)
			(layer "F.CrtYd")
		)
		(fp_rect
			(start -0.508 0.9398)
			(end 0.508 -0.9398)
			(stroke
				(width 0)
				(type default)
			)
			(fill no)
			(layer "F.Fab")
		)
		(pad "1" smd custom
			(at 0 -0.4445)
			(size 0.1397 0.1397)
			(layers "F.Cu" "F.Mask" "F.Paste")
			(net "GATE_FAN2")
			(options
				(clearance outline)
				(anchor circle)
			)
			(primitives
				(gr_poly
					(pts
						(arc
							(start -0.1778 -0.2794)
							(mid -0.249642 -0.249642)
							(end -0.2794 -0.1778)
						)
						(arc
							(start -0.2794 0.1778)
							(mid -0.249642 0.249642)
							(end -0.1778 0.2794)
						)
						(arc
							(start 0.1778 0.2794)
							(mid 0.249642 0.249642)
							(end 0.2794 0.1778)
						)
						(arc
							(start 0.2794 -0.1778)
							(mid 0.249642 -0.249642)
							(end 0.1778 -0.2794)
						)
					)
					(width 0)
					(fill yes)
				)
			)
		)
		(pad "2" smd custom
			(at 0 0.4445)
			(size 0.1397 0.1397)
			(layers "F.Cu" "F.Mask" "F.Paste")
			(net "GATE_FAN2_R")
			(options
				(clearance outline)
				(anchor circle)
			)
			(primitives
				(gr_poly
					(pts
						(arc
							(start -0.1778 -0.2794)
							(mid -0.249642 -0.249642)
							(end -0.2794 -0.1778)
						)
						(arc
							(start -0.2794 0.1778)
							(mid -0.249642 0.249642)
							(end -0.1778 0.2794)
						)
						(arc
							(start 0.1778 0.2794)
							(mid 0.249642 0.249642)
							(end 0.2794 0.1778)
						)
						(arc
							(start 0.2794 -0.1778)
							(mid 0.249642 -0.249642)
							(end 0.1778 -0.2794)
						)
					)
					(width 0)
					(fill yes)
				)
			)
		)
	)
	(footprint ""
		(layer "F.Cu")
		(at 473.583 -20.828 90)
		(property "Reference" "C493"
			(at 0 0 90)
			(layer "F.SilkS")
			(hide yes)
			(effects
				(font
					(size 1.27 1.27)
				)
			)
		)
		(property "Value" "SCD033U25V2KX-GP"
			(at 1.1811 -2.7051 90)
			(unlocked yes)
			(layer "F.Fab")
			(hide yes)
			(effects
				(font
					(size 1.016 1.016)
					(thickness 0.1524)
				)
			)
		)
		(property "Device Type" "C402H22"
			(at 1.1811 -4.2291 90)
			(unlocked yes)
			(layer "F.Fab")
			(hide yes)
			(effects
				(font
					(size 1.016 1.016)
					(thickness 0.1524)
				)
			)
		)
		(duplicate_pad_numbers_are_jumpers no)
		(fp_rect
			(start -0.4318 0.9525)
			(end 0.4318 -0.9525)
			(stroke
				(width 0)
				(type default)
			)
			(fill no)
			(layer "F.CrtYd")
		)
		(fp_rect
			(start -0.4318 0.9525)
			(end 0.4318 -0.9525)
			(stroke
				(width 0)
				(type default)
			)
			(fill no)
			(layer "F.Fab")
		)
		(pad "1" smd custom
			(at 0 -0.4445 90)
			(size 0.1524 0.1524)
			(layers "F.Cu" "F.Mask" "F.Paste")
			(net "SW_HDD_P35")
			(options
				(clearance outline)
				(anchor circle)
			)
			(primitives
				(gr_poly
					(pts
						(arc
							(start 0.3048 -0.2032)
							(mid 0.275042 -0.275042)
							(end 0.2032 -0.3048)
						)
						(arc
							(start -0.2032 -0.3048)
							(mid -0.275042 -0.275042)
							(end -0.3048 -0.2032)
						)
						(arc
							(start -0.3048 0.2032)
							(mid -0.275042 0.275042)
							(end -0.2032 0.3048)
						)
						(arc
							(start 0.2032 0.3048)
							(mid 0.275042 0.275042)
							(end 0.3048 0.2032)
						)
					)
					(width 0)
					(fill yes)
				)
			)
		)
		(pad "2" smd custom
			(at 0 0.4445 90)
			(size 0.1524 0.1524)
			(layers "F.Cu" "F.Mask" "F.Paste")
			(net "GND")
			(options
				(clearance outline)
				(anchor circle)
			)
			(primitives
				(gr_poly
					(pts
						(arc
							(start 0.3048 -0.2032)
							(mid 0.275042 -0.275042)
							(end 0.2032 -0.3048)
						)
						(arc
							(start -0.2032 -0.3048)
							(mid -0.275042 -0.275042)
							(end -0.3048 -0.2032)
						)
						(arc
							(start -0.3048 0.2032)
							(mid -0.275042 0.275042)
							(end -0.2032 0.3048)
						)
						(arc
							(start 0.2032 0.3048)
							(mid 0.275042 0.275042)
							(end 0.3048 0.2032)
						)
					)
					(width 0)
					(fill yes)
				)
			)
		)
	)
)
